# T6G (Grand Teton) — schematic netlist excerpt (pin names and nets, part order shuffled) for the footprints in the layout excerpt that follows; sources: Cadence DE-HDL packaged netlist, KiCad conversion of 04192023_DAF0TMB3IC0_F0TG_MB_C_brd_V02_OCP.brd

R1857  Q_RES  10K 1% CHIP  pkg 0402LF  page 152 : A = P3V3_AUX ; B = P12V_SCM_EN
PR509  Q_RES  1.5 1% EMPTY  pkg 0402LF  page 202 : A = SW_PVDDCR_CPU1_P0_SW4_RC ; B = GND

(kicad_pcb
	(version 20260206)
	(generator "pcbnew")
	(generator_version "10.0")
	(general
		(thickness 1.6)
		(legacy_teardrops no)
	)
	(paper "A4")
	(title_block
		(title "04192023_DAF0TMB3IC0_F0TG_MB_C_brd_V02_OCP.brd")
		(comment 1 "Grand Teton / footprints 2582-2583 of 8354")
	)
	(layers
		(0 "F.Cu" signal "TOP")
		(4 "In1.Cu" signal "GND")
		(6 "In2.Cu" signal "IN1")
		(8 "In3.Cu" signal "GND1")
		(10 "In4.Cu" signal "IN2")
		(12 "In5.Cu" signal "GND2")
		(14 "In6.Cu" signal "IN3")
		(16 "In7.Cu" signal "GND3")
		(18 "In8.Cu" signal "VCC")
		(20 "In9.Cu" signal "VCC1")
		(22 "In10.Cu" signal "GND4")
		(24 "In11.Cu" signal "IN4")
		(26 "In12.Cu" signal "GND5")
		(28 "In13.Cu" signal "IN5")
		(30 "In14.Cu" signal "GND6")
		(32 "In15.Cu" signal "IN6")
		(34 "In16.Cu" signal "GND7")
		(2 "B.Cu" signal "BOTTOM")
		(9 "F.Adhes" user "F.Adhesive")
		(11 "B.Adhes" user "B.Adhesive")
		(13 "F.Paste" user "Package Geometry/Pastemask Top")
		(15 "B.Paste" user "Package Geometry/Pastemask Bottom")
		(5 "F.SilkS" user "Ref Des/Silkscreen Top")
		(7 "B.SilkS" user "Ref Des/Silkscreen Bottom")
		(1 "F.Mask" user "Board Geometry/Soldermask Top")
		(3 "B.Mask" user "Board Geometry/Soldermask Bottom")
		(17 "Dwgs.User" user "User.Drawings")
		(19 "Cmts.User" user "User.Comments")
		(21 "Eco1.User" user "User.Eco1")
		(23 "Eco2.User" user "User.Eco2")
		(25 "Edge.Cuts" user "Board Geometry/Outline")
		(27 "Margin" user)
		(31 "F.CrtYd" user "Package Geometry/Place Bound Top")
		(29 "B.CrtYd" user "Package Geometry/Place Bound Bottom")
		(35 "F.Fab" user "Ref Des/Assembly Top")
		(33 "B.Fab" user "Ref Des/Assembly Bottom")
	)
	(footprint ""
		(layer "F.Cu")
		(at 305.018948 -344.982038 90)
		(property "Reference" "PR509"
			(at 0 0 90)
			(layer "F.SilkS")
			(hide yes)
			(effects
				(font
					(size 1.27 1.27)
				)
			)
		)
		(property "Value" ""
			(at 0 0 90)
			(layer "F.Fab")
			(effects
				(font
					(size 1.27 1.27)
				)
			)
		)
		(duplicate_pad_numbers_are_jumpers no)
		(fp_line
			(start 0.7874 -0.4064)
			(end 0.7874 0.4064)
			(stroke
				(width 0.1524)
				(type default)
			)
			(layer "F.SilkS")
		)
		(fp_line
			(start -0.7874 -0.4064)
			(end 0.7874 -0.4064)
			(stroke
				(width 0.1524)
				(type default)
			)
			(layer "F.SilkS")
		)
		(fp_line
			(start 0.7874 0.4064)
			(end -0.7874 0.4064)
			(stroke
				(width 0.1524)
				(type default)
			)
			(layer "F.SilkS")
		)
		(fp_line
			(start -0.7874 0.4064)
			(end -0.7874 -0.4064)
			(stroke
				(width 0.1524)
				(type default)
			)
			(layer "F.SilkS")
		)
		(fp_line
			(start -0.12065 -0.305054)
			(end -0.12065 -0.2794)
			(stroke
				(width 0.1)
				(type default)
			)
			(layer "F.Fab")
		)
		(fp_line
			(start -0.67945 -0.305054)
			(end -0.12065 -0.305054)
			(stroke
				(width 0.1)
				(type default)
			)
			(layer "F.Fab")
		)
		(fp_line
			(start 0.67945 -0.3048)
			(end 0.67945 0.3048)
			(stroke
				(width 0.1)
				(type default)
			)
			(layer "F.Fab")
		)
		(fp_line
			(start 0.12065 -0.3048)
			(end 0.67945 -0.3048)
			(stroke
				(width 0.1)
				(type default)
			)
			(layer "F.Fab")
		)
		(fp_line
			(start 0.12065 -0.2794)
			(end 0.12065 -0.3048)
			(stroke
				(width 0.1)
				(type default)
			)
			(layer "F.Fab")
		)
		(fp_line
			(start -0.12065 -0.2794)
			(end 0.12065 -0.2794)
			(stroke
				(width 0.1)
				(type default)
			)
			(layer "F.Fab")
		)
		(fp_line
			(start 0.120396 0.2794)
			(end -0.12065 0.2794)
			(stroke
				(width 0.1)
				(type default)
			)
			(layer "F.Fab")
		)
		(fp_line
			(start -0.12065 0.2794)
			(end -0.12065 0.3048)
			(stroke
				(width 0.1)
				(type default)
			)
			(layer "F.Fab")
		)
		(fp_line
			(start 0.67945 0.3048)
			(end 0.120396 0.3048)
			(stroke
				(width 0.1)
				(type default)
			)
			(layer "F.Fab")
		)
		(fp_line
			(start 0.120396 0.3048)
			(end 0.120396 0.2794)
			(stroke
				(width 0.1)
				(type default)
			)
			(layer "F.Fab")
		)
		(fp_line
			(start -0.12065 0.3048)
			(end -0.67945 0.3048)
			(stroke
				(width 0.1)
				(type default)
			)
			(layer "F.Fab")
		)
		(fp_line
			(start -0.67945 0.3048)
			(end -0.67945 -0.305054)
			(stroke
				(width 0.1)
				(type default)
			)
			(layer "F.Fab")
		)
		(pad "1" smd circle
			(at -0.40005 0 90)
			(size 0 0)
			(layers "F.Cu" "F.Mask" "F.Paste")
			(net "SW_PVDDCR_CPU1_P0_SW4_RC")
		)
		(pad "2" smd circle
			(at 0.40005 0 90)
			(size 0 0)
			(layers "F.Cu" "F.Mask" "F.Paste")
			(net "GND")
		)
	)
	(footprint ""
		(layer "F.Cu")
		(at 197.180962 -39.046912)
		(property "Reference" "R1857"
			(at 0 0 0)
			(layer "F.SilkS")
			(hide yes)
			(effects
				(font
					(size 1.27 1.27)
				)
			)
		)
		(property "Value" ""
			(at 0 0 0)
			(layer "F.Fab")
			(effects
				(font
					(size 1.27 1.27)
				)
			)
		)
		(duplicate_pad_numbers_are_jumpers no)
		(fp_line
			(start -0.7874 -0.4064)
			(end 0.7874 -0.4064)
			(stroke
				(width 0.1524)
				(type default)
			)
			(layer "F.SilkS")
		)
		(fp_line
			(start -0.7874 0.4064)
			(end -0.7874 -0.4064)
			(stroke
				(width 0.1524)
				(type default)
			)
			(layer "F.SilkS")
		)
		(fp_line
			(start 0.7874 -0.4064)
			(end 0.7874 0.4064)
			(stroke
				(width 0.1524)
				(type default)
			)
			(layer "F.SilkS")
		)
		(fp_line
			(start 0.7874 0.4064)
			(end -0.7874 0.4064)
			(stroke
				(width 0.1524)
				(type default)
			)
			(layer "F.SilkS")
		)
		(fp_line
			(start -0.67945 -0.305054)
			(end -0.12065 -0.305054)
			(stroke
				(width 0.1)
				(type default)
			)
			(layer "F.Fab")
		)
		(fp_line
			(start -0.67945 0.3048)
			(end -0.67945 -0.305054)
			(stroke
				(width 0.1)
				(type default)
			)
			(layer "F.Fab")
		)
		(fp_line
			(start -0.12065 -0.305054)
			(end -0.12065 -0.2794)
			(stroke
				(width 0.1)
				(type default)
			)
			(layer "F.Fab")
		)
		(fp_line
			(start -0.12065 -0.2794)
			(end 0.12065 -0.2794)
			(stroke
				(width 0.1)
				(type default)
			)
			(layer "F.Fab")
		)
		(fp_line
			(start -0.12065 0.2794)
			(end -0.12065 0.3048)
			(stroke
				(width 0.1)
				(type default)
			)
			(layer "F.Fab")
		)
		(fp_line
			(start -0.12065 0.3048)
			(end -0.67945 0.3048)
			(stroke
				(width 0.1)
				(type default)
			)
			(layer "F.Fab")
		)
		(fp_line
			(start 0.120396 0.2794)
			(end -0.12065 0.2794)
			(stroke
				(width 0.1)
				(type default)
			)
			(layer "F.Fab")
		)
		(fp_line
			(start 0.120396 0.3048)
			(end 0.120396 0.2794)
			(stroke
				(width 0.1)
				(type default)
			)
			(layer "F.Fab")
		)
		(fp_line
			(start 0.12065 -0.3048)
			(end 0.67945 -0.3048)
			(stroke
				(width 0.1)
				(type default)
			)
			(layer "F.Fab")
		)
		(fp_line
			(start 0.12065 -0.2794)
			(end 0.12065 -0.3048)
			(stroke
				(width 0.1)
				(type default)
			)
			(layer "F.Fab")
		)
		(fp_line
			(start 0.67945 -0.3048)
			(end 0.67945 0.3048)
			(stroke
				(width 0.1)
				(type default)
			)
			(layer "F.Fab")
		)
		(fp_line
			(start 0.67945 0.3048)
			(end 0.120396 0.3048)
			(stroke
				(width 0.1)
				(type default)
			)
			(layer "F.Fab")
		)
		(pad "1" smd circle
			(at -0.40005 0)
			(size 0 0)
			(layers "F.Cu" "F.Mask" "F.Paste")
			(net "P3V3_AUX")
		)
		(pad "2" smd circle
			(at 0.40005 0)
			(size 0 0)
			(layers "F.Cu" "F.Mask" "F.Paste")
			(net "P12V_SCM_EN")
		)
	)
)
